(kicad_pcb
	(version 20260206)
	(generator "pcbnew")
	(generator_version "10.0")
	(general
		(thickness 1.6)
		(legacy_teardrops no)
	)
	(paper "A4")
	(title_block
		(title "9054_F0T_PDB_BD_GPU_F_V04_1213_1550_OCP.brd")
		(comment 1 "Grand Teton / footprints 80-86 of 608")
	)
	(layers
		(0 "F.Cu" signal "TOP")
		(4 "In1.Cu" signal "GND")
		(6 "In2.Cu" signal "IN1")
		(8 "In3.Cu" signal "GND1")
		(10 "In4.Cu" signal "VCC")
		(12 "In5.Cu" signal "VCC1")
		(14 "In6.Cu" signal "GND2")
		(16 "In7.Cu" signal "IN2")
		(18 "In8.Cu" signal "GND3")
		(2 "B.Cu" signal "BOTTOM")
		(9 "F.Adhes" user "F.Adhesive")
		(11 "B.Adhes" user "B.Adhesive")
		(13 "F.Paste" user "Package Geometry/Pastemask Top")
		(15 "B.Paste" user "Package Geometry/Pastemask Bottom")
		(5 "F.SilkS" user "Ref Des/Silkscreen Top")
		(7 "B.SilkS" user "Ref Des/Silkscreen Bottom")
		(1 "F.Mask" user "Board Geometry/Soldermask Top")
		(3 "B.Mask" user "Board Geometry/Soldermask Bottom")
		(17 "Dwgs.User" user "User.Drawings")
		(19 "Cmts.User" user "User.Comments")
		(21 "Eco1.User" user "User.Eco1")
		(23 "Eco2.User" user "User.Eco2")
		(25 "Edge.Cuts" user "Board Geometry/Outline")
		(27 "Margin" user)
		(31 "F.CrtYd" user "Package Geometry/Place Bound Top")
		(29 "B.CrtYd" user "Package Geometry/Place Bound Bottom")
		(35 "F.Fab" user "Ref Des/Assembly Top")
		(33 "B.Fab" user "Ref Des/Assembly Bottom")
	)
	(footprint ""
		(layer "F.Cu")
		(at 306.7304 -71.755)
		(property "Reference" "PR6957"
			(at 0 0 0)
			(layer "F.SilkS")
			(hide yes)
			(effects
				(font
					(size 1.27 1.27)
				)
			)
		)
		(property "Value" ""
			(at 0 0 0)
			(layer "F.Fab")
			(effects
				(font
					(size 1.27 1.27)
				)
			)
		)
		(duplicate_pad_numbers_are_jumpers no)
		(fp_line
			(start -1.2954 -0.5842)
			(end 1.2954 -0.5842)
			(stroke
				(width 0.1524)
				(type default)
			)
			(layer "F.SilkS")
		)
		(fp_line
			(start -1.2954 0.5842)
			(end -1.2954 -0.5842)
			(stroke
				(width 0.1524)
				(type default)
			)
			(layer "F.SilkS")
		)
		(fp_line
			(start 1.2954 -0.5842)
			(end 1.2954 0.5842)
			(stroke
				(width 0.1524)
				(type default)
			)
			(layer "F.SilkS")
		)
		(fp_line
			(start 1.2954 0.5842)
			(end -1.2954 0.5842)
			(stroke
				(width 0.1524)
				(type default)
			)
			(layer "F.SilkS")
		)
		(fp_line
			(start -1.1938 -0.406654)
			(end -0.8636 -0.406654)
			(stroke
				(width 0.1)
				(type default)
			)
			(layer "F.Fab")
		)
		(fp_line
			(start -1.1938 0.4064)
			(end -1.1938 -0.406654)
			(stroke
				(width 0.1)
				(type default)
			)
			(layer "F.Fab")
		)
		(fp_line
			(start -0.8636 -0.4572)
			(end 0.8636 -0.4572)
			(stroke
				(width 0.1)
				(type default)
			)
			(layer "F.Fab")
		)
		(fp_line
			(start -0.8636 -0.406654)
			(end -0.8636 -0.4572)
			(stroke
				(width 0.1)
				(type default)
			)
			(layer "F.Fab")
		)
		(fp_line
			(start -0.8636 0.4064)
			(end -1.1938 0.4064)
			(stroke
				(width 0.1)
				(type default)
			)
			(layer "F.Fab")
		)
		(fp_line
			(start -0.8636 0.4318)
			(end -0.8636 0.4064)
			(stroke
				(width 0.1)
				(type default)
			)
			(layer "F.Fab")
		)
		(fp_line
			(start -0.8636 0.4572)
			(end -0.8636 0.4318)
			(stroke
				(width 0.1)
				(type default)
			)
			(layer "F.Fab")
		)
		(fp_line
			(start 0.8636 -0.4572)
			(end 0.8636 -0.406654)
			(stroke
				(width 0.1)
				(type default)
			)
			(layer "F.Fab")
		)
		(fp_line
			(start 0.8636 -0.406654)
			(end 1.1938 -0.406654)
			(stroke
				(width 0.1)
				(type default)
			)
			(layer "F.Fab")
		)
		(fp_line
			(start 0.8636 0.4064)
			(end 0.8636 0.4572)
			(stroke
				(width 0.1)
				(type default)
			)
			(layer "F.Fab")
		)
		(fp_line
			(start 0.8636 0.4572)
			(end -0.8636 0.4572)
			(stroke
				(width 0.1)
				(type default)
			)
			(layer "F.Fab")
		)
		(fp_line
			(start 1.1938 -0.406654)
			(end 1.1938 0.4064)
			(stroke
				(width 0.1)
				(type default)
			)
			(layer "F.Fab")
		)
		(fp_line
			(start 1.1938 0.4064)
			(end 0.8636 0.4064)
			(stroke
				(width 0.1)
				(type default)
			)
			(layer "F.Fab")
		)
		(pad "1" smd rect
			(at -0.7366 0 270)
			(size 0.7112 0.8128)
			(layers "F.Cu" "F.Mask" "F.Paste")
			(net "P52V_HS_4287_S1N")
		)
		(pad "2" smd rect
			(at 0.7366 0 270)
			(size 0.7112 0.8128)
			(layers "F.Cu" "F.Mask" "F.Paste")
			(net "P52V_HS1_SENSE_N_R1")
		)
	)
	(footprint ""
		(layer "F.Cu")
		(at 424.999912 -104.549956)
		(property "Reference" "H23"
			(at -0.794512 8.818626 0)
			(unlocked yes)
			(layer "F.SilkS")
			(effects
				(font
					(size 0.7874 0.5842)
					(thickness 0.1524)
				)
				(justify left)
			)
		)
		(property "Value" ""
			(at 0 0 0)
			(layer "F.Fab")
			(effects
				(font
					(size 1.27 1.27)
				)
			)
		)
		(duplicate_pad_numbers_are_jumpers no)
		(fp_circle
			(center 0 0)
			(end 7.999984 0)
			(stroke
				(width 0.1524)
				(type default)
			)
			(fill no)
			(layer "F.SilkS")
		)
		(fp_circle
			(center 0 0)
			(end 7.999984 0)
			(stroke
				(width 0.1524)
				(type default)
			)
			(fill no)
			(layer "B.SilkS")
		)
		(fp_circle
			(center 0 0)
			(end 7.999984 0)
			(stroke
				(width 0.1)
				(type default)
			)
			(fill no)
			(layer "B.Fab")
		)
		(fp_circle
			(center 0 0)
			(end 7.999984 0)
			(stroke
				(width 0.1)
				(type default)
			)
			(fill no)
			(layer "F.Fab")
		)
		(pad "" np_thru_hole circle
			(at 0 0)
			(size 4.0132 4.0132)
			(drill 4.0132)
			(layers "*.Cu" "*.Mask")
			(clearance 0.381)
			(thermal_gap 0.381)
		)
		(pad "2" thru_hole circle
			(at 0 -3.50012)
			(size 0.762 0.762)
			(drill 0.5588)
			(layers "*.Cu" "*.Mask")
			(remove_unused_layers no)
			(net "GND")
			(clearance 0.1524)
			(thermal_gap 0.1524)
		)
		(pad "3" thru_hole circle
			(at -2.500122 -2.500122)
			(size 0.762 0.762)
			(drill 0.5588)
			(layers "*.Cu" "*.Mask")
			(remove_unused_layers no)
			(net "GND")
			(clearance 0.1524)
			(thermal_gap 0.1524)
		)
		(pad "4" thru_hole circle
			(at -3.50012 0)
			(size 0.762 0.762)
			(drill 0.5588)
			(layers "*.Cu" "*.Mask")
			(remove_unused_layers no)
			(net "GND")
			(clearance 0.1524)
			(thermal_gap 0.1524)
		)
		(pad "5" thru_hole circle
			(at -2.500122 2.500122)
			(size 0.762 0.762)
			(drill 0.5588)
			(layers "*.Cu" "*.Mask")
			(remove_unused_layers no)
			(net "GND")
			(clearance 0.1524)
			(thermal_gap 0.1524)
		)
		(pad "6" thru_hole circle
			(at 0 3.50012)
			(size 0.762 0.762)
			(drill 0.5588)
			(layers "*.Cu" "*.Mask")
			(remove_unused_layers no)
			(net "GND")
			(clearance 0.1524)
			(thermal_gap 0.1524)
		)
		(pad "7" thru_hole circle
			(at 2.500122 2.500122)
			(size 0.762 0.762)
			(drill 0.5588)
			(layers "*.Cu" "*.Mask")
			(remove_unused_layers no)
			(net "GND")
			(clearance 0.1524)
			(thermal_gap 0.1524)
		)
		(pad "8" thru_hole circle
			(at 3.50012 0)
			(size 0.762 0.762)
			(drill 0.5588)
			(layers "*.Cu" "*.Mask")
			(remove_unused_layers no)
			(net "GND")
			(clearance 0.1524)
			(thermal_gap 0.1524)
		)
		(pad "9" thru_hole circle
			(at 2.500122 -2.500122)
			(size 0.762 0.762)
			(drill 0.5588)
			(layers "*.Cu" "*.Mask")
			(remove_unused_layers no)
			(net "GND")
			(clearance 0.1524)
			(thermal_gap 0.1524)
		)
		(zone
			(layers "F.Cu" "B.Cu" "In1.Cu" "In2.Cu" "In3.Cu" "In4.Cu" "In5.Cu" "In6.Cu"
				"In7.Cu" "In8.Cu"
			)
			(hatch none 0.5)
			(connect_pads
				(clearance 0)
			)
			(min_thickness 0.25)
			(keepout
				(tracks not_allowed)
				(vias allowed)
				(pads allowed)
				(copperpour not_allowed)
				(footprints allowed)
			)
			(placement
				(enabled no)
				(sheetname "")
			)
			(fill
				(thermal_gap 0.5)
				(thermal_bridge_width 0.5)
				(island_removal_mode 0)
			)
			(polygon
				(pts
					(arc
						(start 427.514512 -104.549956)
						(mid 422.485312 -104.549956)
						(end 427.514512 -104.549956)
					)
				)
			)
		)
	)
	(footprint ""
		(layer "F.Cu")
		(at 414.02 -41.529 180)
		(property "Reference" "R5928"
			(at 0 0 180)
			(layer "F.SilkS")
			(hide yes)
			(effects
				(font
					(size 1.27 1.27)
				)
			)
		)
		(property "Value" ""
			(at 0 0 180)
			(layer "F.Fab")
			(effects
				(font
					(size 1.27 1.27)
				)
			)
		)
		(duplicate_pad_numbers_are_jumpers no)
		(fp_line
			(start 0.7874 0.4064)
			(end -0.7874 0.4064)
			(stroke
				(width 0.1524)
				(type default)
			)
			(layer "F.SilkS")
		)
		(fp_line
			(start 0.7874 -0.4064)
			(end 0.7874 0.4064)
			(stroke
				(width 0.1524)
				(type default)
			)
			(layer "F.SilkS")
		)
		(fp_line
			(start -0.7874 0.4064)
			(end -0.7874 -0.4064)
			(stroke
				(width 0.1524)
				(type default)
			)
			(layer "F.SilkS")
		)
		(fp_line
			(start -0.7874 -0.4064)
			(end 0.7874 -0.4064)
			(stroke
				(width 0.1524)
				(type default)
			)
			(layer "F.SilkS")
		)
		(fp_line
			(start 0.67945 0.3048)
			(end 0.120396 0.3048)
			(stroke
				(width 0.1)
				(type default)
			)
			(layer "F.Fab")
		)
		(fp_line
			(start 0.67945 -0.3048)
			(end 0.67945 0.3048)
			(stroke
				(width 0.1)
				(type default)
			)
			(layer "F.Fab")
		)
		(fp_line
			(start 0.12065 -0.2794)
			(end 0.12065 -0.3048)
			(stroke
				(width 0.1)
				(type default)
			)
			(layer "F.Fab")
		)
		(fp_line
			(start 0.12065 -0.3048)
			(end 0.67945 -0.3048)
			(stroke
				(width 0.1)
				(type default)
			)
			(layer "F.Fab")
		)
		(fp_line
			(start 0.120396 0.3048)
			(end 0.120396 0.2794)
			(stroke
				(width 0.1)
				(type default)
			)
			(layer "F.Fab")
		)
		(fp_line
			(start 0.120396 0.2794)
			(end -0.12065 0.2794)
			(stroke
				(width 0.1)
				(type default)
			)
			(layer "F.Fab")
		)
		(fp_line
			(start -0.12065 0.3048)
			(end -0.67945 0.3048)
			(stroke
				(width 0.1)
				(type default)
			)
			(layer "F.Fab")
		)
		(fp_line
			(start -0.12065 0.2794)
			(end -0.12065 0.3048)
			(stroke
				(width 0.1)
				(type default)
			)
			(layer "F.Fab")
		)
		(fp_line
			(start -0.12065 -0.2794)
			(end 0.12065 -0.2794)
			(stroke
				(width 0.1)
				(type default)
			)
			(layer "F.Fab")
		)
		(fp_line
			(start -0.12065 -0.305054)
			(end -0.12065 -0.2794)
			(stroke
				(width 0.1)
				(type default)
			)
			(layer "F.Fab")
		)
		(fp_line
			(start -0.67945 0.3048)
			(end -0.67945 -0.305054)
			(stroke
				(width 0.1)
				(type default)
			)
			(layer "F.Fab")
		)
		(fp_line
			(start -0.67945 -0.305054)
			(end -0.12065 -0.305054)
			(stroke
				(width 0.1)
				(type default)
			)
			(layer "F.Fab")
		)
		(pad "1" smd circle
			(at -0.40005 0 180)
			(size 0 0)
			(layers "F.Cu" "F.Mask" "F.Paste")
			(net "PRSNT_FAN_BP1_N")
		)
		(pad "2" smd circle
			(at 0.40005 0 180)
			(size 0 0)
			(layers "F.Cu" "F.Mask" "F.Paste")
			(net "PRSNT_FAN_BP1_R_N")
		)
	)
	(footprint ""
		(layer "F.Cu")
		(at 450.41312 -87.36838 180)
		(property "Reference" "R394"
			(at 0 0 180)
			(layer "F.SilkS")
			(hide yes)
			(effects
				(font
					(size 1.27 1.27)
				)
			)
		)
		(property "Value" ""
			(at 0 0 180)
			(layer "F.Fab")
			(effects
				(font
					(size 1.27 1.27)
				)
			)
		)
		(duplicate_pad_numbers_are_jumpers no)
		(fp_line
			(start 0.7874 0.4064)
			(end -0.7874 0.4064)
			(stroke
				(width 0.1524)
				(type default)
			)
			(layer "F.SilkS")
		)
		(fp_line
			(start 0.7874 -0.4064)
			(end 0.7874 0.4064)
			(stroke
				(width 0.1524)
				(type default)
			)
			(layer "F.SilkS")
		)
		(fp_line
			(start -0.7874 0.4064)
			(end -0.7874 -0.4064)
			(stroke
				(width 0.1524)
				(type default)
			)
			(layer "F.SilkS")
		)
		(fp_line
			(start -0.7874 -0.4064)
			(end 0.7874 -0.4064)
			(stroke
				(width 0.1524)
				(type default)
			)
			(layer "F.SilkS")
		)
		(fp_line
			(start 0.67945 0.3048)
			(end 0.120396 0.3048)
			(stroke
				(width 0.1)
				(type default)
			)
			(layer "F.Fab")
		)
		(fp_line
			(start 0.67945 -0.3048)
			(end 0.67945 0.3048)
			(stroke
				(width 0.1)
				(type default)
			)
			(layer "F.Fab")
		)
		(fp_line
			(start 0.12065 -0.2794)
			(end 0.12065 -0.3048)
			(stroke
				(width 0.1)
				(type default)
			)
			(layer "F.Fab")
		)
		(fp_line
			(start 0.12065 -0.3048)
			(end 0.67945 -0.3048)
			(stroke
				(width 0.1)
				(type default)
			)
			(layer "F.Fab")
		)
		(fp_line
			(start 0.120396 0.3048)
			(end 0.120396 0.2794)
			(stroke
				(width 0.1)
				(type default)
			)
			(layer "F.Fab")
		)
		(fp_line
			(start 0.120396 0.2794)
			(end -0.12065 0.2794)
			(stroke
				(width 0.1)
				(type default)
			)
			(layer "F.Fab")
		)
		(fp_line
			(start -0.12065 0.3048)
			(end -0.67945 0.3048)
			(stroke
				(width 0.1)
				(type default)
			)
			(layer "F.Fab")
		)
		(fp_line
			(start -0.12065 0.2794)
			(end -0.12065 0.3048)
			(stroke
				(width 0.1)
				(type default)
			)
			(layer "F.Fab")
		)
		(fp_line
			(start -0.12065 -0.2794)
			(end 0.12065 -0.2794)
			(stroke
				(width 0.1)
				(type default)
			)
			(layer "F.Fab")
		)
		(fp_line
			(start -0.12065 -0.305054)
			(end -0.12065 -0.2794)
			(stroke
				(width 0.1)
				(type default)
			)
			(layer "F.Fab")
		)
		(fp_line
			(start -0.67945 0.3048)
			(end -0.67945 -0.305054)
			(stroke
				(width 0.1)
				(type default)
			)
			(layer "F.Fab")
		)
		(fp_line
			(start -0.67945 -0.305054)
			(end -0.12065 -0.305054)
			(stroke
				(width 0.1)
				(type default)
			)
			(layer "F.Fab")
		)
		(pad "1" smd circle
			(at -0.40005 0 180)
			(size 0 0)
			(layers "F.Cu" "F.Mask" "F.Paste")
			(net "P12V_HPDB_PWRGD")
		)
		(pad "2" smd circle
			(at 0.40005 0 180)
			(size 0 0)
			(layers "F.Cu" "F.Mask" "F.Paste")
			(net "P3V3_HPDB_EN")
		)
	)
	(footprint ""
		(layer "F.Cu")
		(at 397.637 -99.06)
		(property "Reference" "PC33"
			(at -8.1026 -4.79933 0)
			(unlocked yes)
			(layer "F.SilkS")
			(effects
				(font
					(size 0.7874 0.5842)
					(thickness 0.1524)
				)
				(justify left)
			)
		)
		(property "Value" ""
			(at 0 0 0)
			(layer "F.Fab")
			(effects
				(font
					(size 1.27 1.27)
				)
			)
		)
		(duplicate_pad_numbers_are_jumpers no)
		(fp_line
			(start -9.253728 3.750056)
			(end 9.249918 3.750056)
			(stroke
				(width 0.1524)
				(type default)
			)
			(layer "F.SilkS")
		)
		(fp_line
			(start 0 3.750056)
			(end -9.253728 3.750056)
			(stroke
				(width 0.1524)
				(type default)
			)
			(layer "F.SilkS")
		)
		(fp_circle
			(center 0 3.750056)
			(end 9.249918 3.750056)
			(stroke
				(width 0.1524)
				(type default)
			)
			(fill no)
			(layer "F.SilkS")
		)
		(fp_poly
			(pts
				(arc
					(start 9.249918 3.750056)
					(mid 0 12.999974)
					(end -9.249918 3.750056)
				)
			)
			(stroke
				(width 0)
				(type default)
			)
			(fill yes)
			(layer "F.SilkS")
		)
		(fp_circle
			(center 0 3.750056)
			(end 9.249918 3.750056)
			(stroke
				(width 0.1)
				(type default)
			)
			(fill no)
			(layer "F.Fab")
		)
		(pad "1" thru_hole rect
			(at 0 0)
			(size 1.778 1.778)
			(drill 1.27)
			(layers "*.Cu" "*.Mask")
			(remove_unused_layers no)
			(net "P52V_HS1")
			(clearance 0)
			(padstack
				(mode front_inner_back)
				(layer "Inner"
					(shape circle)
					(size 1.778 1.778)
					(clearance 0)
				)
				(layer "B.Cu"
					(shape rect)
					(size 1.778 1.778)
					(clearance 0)
				)
			)
		)
		(pad "2" thru_hole circle
			(at 0 7.500112)
			(size 1.778 1.778)
			(drill 1.27)
			(layers "*.Cu" "*.Mask")
			(remove_unused_layers no)
			(net "GND")
			(clearance 0)
		)
	)
	(footprint ""
		(layer "F.Cu")
		(at 42.36339 -139.7)
		(property "Reference" "PC34"
			(at 6.104128 -4.407408 0)
			(unlocked yes)
			(layer "F.SilkS")
			(effects
				(font
					(size 0.7874 0.5842)
					(thickness 0.1524)
				)
				(justify left)
			)
		)
		(property "Value" ""
			(at 0 0 0)
			(layer "F.Fab")
			(effects
				(font
					(size 1.27 1.27)
				)
			)
		)
		(duplicate_pad_numbers_are_jumpers no)
		(fp_line
			(start -9.253728 3.750056)
			(end 9.249918 3.750056)
			(stroke
				(width 0.1524)
				(type default)
			)
			(layer "F.SilkS")
		)
		(fp_line
			(start 0 3.750056)
			(end -9.253728 3.750056)
			(stroke
				(width 0.1524)
				(type default)
			)
			(layer "F.SilkS")
		)
		(fp_circle
			(center 0 3.750056)
			(end 9.249918 3.750056)
			(stroke
				(width 0.1524)
				(type default)
			)
			(fill no)
			(layer "F.SilkS")
		)
		(fp_poly
			(pts
				(arc
					(start 9.249918 3.750056)
					(mid 0 12.999974)
					(end -9.249918 3.750056)
				)
			)
			(stroke
				(width 0)
				(type default)
			)
			(fill yes)
			(layer "F.SilkS")
		)
		(fp_circle
			(center 0 3.750056)
			(end 9.249918 3.750056)
			(stroke
				(width 0.1)
				(type default)
			)
			(fill no)
			(layer "F.Fab")
		)
		(pad "1" thru_hole rect
			(at 0 0)
			(size 1.778 1.778)
			(drill 1.27)
			(layers "*.Cu" "*.Mask")
			(remove_unused_layers no)
			(net "P52V_HS2")
			(clearance 0)
			(padstack
				(mode front_inner_back)
				(layer "Inner"
					(shape circle)
					(size 1.778 1.778)
					(clearance 0)
				)
				(layer "B.Cu"
					(shape rect)
					(size 1.778 1.778)
					(clearance 0)
				)
			)
		)
		(pad "2" thru_hole circle
			(at 0 7.500112)
			(size 1.778 1.778)
			(drill 1.27)
			(layers "*.Cu" "*.Mask")
			(remove_unused_layers no)
			(net "GND")
			(clearance 0)
		)
	)
	(footprint ""
		(layer "F.Cu")
		(at 80.000094 -142.499842 180)
		(property "Reference" "H3"
			(at 0.752094 -5.366512 0)
			(unlocked yes)
			(layer "F.SilkS")
			(effects
				(font
					(size 0.7874 0.5842)
					(thickness 0.1524)
				)
				(justify left)
			)
		)
		(property "Value" ""
			(at 0 0 180)
			(layer "F.Fab")
			(effects
				(font
					(size 1.27 1.27)
				)
			)
		)
		(duplicate_pad_numbers_are_jumpers no)
		(pad "1" thru_hole oval
			(at 0 0 180)
			(size 9.017 14.0208)
			(drill 3.0226
				(offset 0 2.499868)
			)
			(layers "*.Cu" "*.Mask")
			(remove_unused_layers no)
			(net "GND")
			(clearance -1.500378)
			(padstack
				(mode front_inner_back)
				(layer "Inner"
					(shape circle)
					(size 0 0)
					(clearance 0)
				)
				(layer "B.Cu"
					(shape oval)
					(size 9.017 14.0208)
					(offset 0 2.499868)
					(clearance -1.500378)
				)
			)
		)
	)
)
